G04 ================== begin FILE IDENTIFICATION RECORD ==================*
G04 Layout Name:  15669-1.brd*
G04 Film Name:    SE_REF_L3*
G04 File Format:  Gerber RS274X*
G04 File Origin:  Cadence Allegro 16.5-S056*
G04 Origin Date:  Wed Nov 16 04:09:18 2016*
G04 *
G04 Layer:  BOARD GEOMETRY/SE_REF_L3_TBL*
G04 Layer:  BOARD GEOMETRY/SE_REF_L3_L3*
G04 Layer:  BOARD GEOMETRY/PANEL_OUTLINE*
G04 *
G04 Offset:    (0.00 0.00)*
G04 Mirror:    No*
G04 Mode:      Positive*
G04 Rotation:  0*
G04 FullContactRelief:  No*
G04 UndefLineWidth:     6.00*
G04 ================== end FILE IDENTIFICATION RECORD ====================*
%FSLAX35Y35*MOIN*%
%IR0*IPPOS*OFA0.00000B0.00000*MIA0B0*SFA1.00000B1.00000*%
%ADD10C,.02*%
%ADD11C,.006*%
G75*
%LPD*%
G75*
G54D10*
G01X1178253Y1923126D02*
X1895753D01*
G01X1178253Y1888476D02*
X1895753D01*
G01X1178253Y1957776D02*
Y1888476D01*
G01Y1957776D02*
X1895753D01*
G01X1353253D02*
Y1888476D01*
G01X1580753Y1957776D02*
Y1888476D01*
G01X1685753Y1957776D02*
Y1888476D01*
G01X1895753Y1957776D02*
Y1888476D01*
G54D11*
G01X-84302Y-32800D02*
Y-50300D01*
G01X-89324Y-32800D02*
X-79280D01*
G01X-70514Y-50300D02*
Y-32800D01*
G01Y-41258D02*
X-69422Y-39800D01*
X-68330Y-38925D01*
X-66584Y-38634D01*
X-65274Y-38925D01*
X-63745Y-40092D01*
X-63090Y-41842D01*
Y-50300D01*
G01X-49302Y-38634D02*
Y-50300D01*
G01Y-33967D02*
X-49739Y-33675D01*
Y-33092D01*
X-49302Y-32800D01*
X-48865Y-33092D01*
Y-33675D01*
X-49302Y-33967D01*
G01X-35077Y-48259D02*
X-33985Y-49425D01*
X-32457Y-50300D01*
X-31147D01*
X-29837Y-49717D01*
X-28964Y-48842D01*
X-28527Y-47676D01*
X-28745Y-45925D01*
X-29619Y-45050D01*
X-33549Y-43300D01*
X-34422Y-41258D01*
X-33985Y-39800D01*
X-33112Y-38925D01*
X-31802Y-38634D01*
X-30492Y-38925D01*
X-29182Y-39800D01*
G01X141Y-54675D02*
X1670Y-55842D01*
X3416Y-56133D01*
X4944Y-55842D01*
X6255Y-54384D01*
X7128Y-52342D01*
Y-38634D01*
G01Y-40967D02*
X6255Y-39800D01*
X4944Y-38925D01*
X3416Y-38634D01*
X1670Y-39217D01*
X578Y-40383D01*
X-296Y-42425D01*
X-732Y-44467D01*
X-514Y-46217D01*
X360Y-48259D01*
X1670Y-49717D01*
X3416Y-50300D01*
X4726Y-50008D01*
X6255Y-48842D01*
X7128Y-47676D01*
G01X17423Y-42425D02*
X24410D01*
X23755Y-40383D01*
X22663Y-39217D01*
X21135Y-38634D01*
X19606Y-38925D01*
X18296Y-39800D01*
X17423Y-41842D01*
X16986Y-43592D01*
Y-45342D01*
X17423Y-47092D01*
X18515Y-48842D01*
X19825Y-50008D01*
X21353Y-50300D01*
X22881Y-49717D01*
X24410Y-47967D01*
G01X35141Y-50300D02*
Y-38634D01*
G01Y-40967D02*
X36233Y-39800D01*
X37325Y-38925D01*
X38853Y-38634D01*
X39944Y-38925D01*
X41255Y-39800D01*
G01X51768Y-50300D02*
Y-32800D01*
G01Y-41550D02*
X52860Y-39800D01*
X54170Y-38925D01*
X55480Y-38634D01*
X57444Y-39217D01*
X58755Y-40383D01*
X59628Y-42425D01*
Y-44758D01*
X59191Y-47092D01*
X58318Y-48842D01*
X56790Y-50008D01*
X55480Y-50300D01*
X54170Y-50008D01*
X52860Y-49134D01*
X51768Y-47676D01*
G01X69923Y-42425D02*
X76910D01*
X76255Y-40383D01*
X75163Y-39217D01*
X73635Y-38634D01*
X72106Y-38925D01*
X70796Y-39800D01*
X69923Y-41842D01*
X69486Y-43592D01*
Y-45342D01*
X69923Y-47092D01*
X71015Y-48842D01*
X72325Y-50008D01*
X73853Y-50300D01*
X75381Y-49717D01*
X76910Y-47967D01*
G01X87641Y-50300D02*
Y-38634D01*
G01Y-40967D02*
X88733Y-39800D01*
X89825Y-38925D01*
X91353Y-38634D01*
X92444Y-38925D01*
X93755Y-39800D01*
G01X125698Y-38634D02*
Y-50300D01*
G01Y-33967D02*
X125261Y-33675D01*
Y-33092D01*
X125698Y-32800D01*
X126135Y-33092D01*
Y-33675D01*
X125698Y-33967D01*
G01X139923Y-48259D02*
X141015Y-49425D01*
X142543Y-50300D01*
X143853D01*
X145163Y-49717D01*
X146036Y-48842D01*
X146473Y-47676D01*
X146255Y-45925D01*
X145381Y-45050D01*
X141451Y-43300D01*
X140578Y-41258D01*
X141015Y-39800D01*
X141888Y-38925D01*
X143198Y-38634D01*
X144508Y-38925D01*
X145818Y-39800D01*
G01X174704Y-54675D02*
X176233Y-55842D01*
X177543Y-56133D01*
X179290Y-55550D01*
X180600Y-54092D01*
X181255Y-51466D01*
Y-38634D01*
G01Y-33967D02*
X180818Y-33675D01*
Y-33092D01*
X181255Y-32800D01*
X181691Y-33092D01*
Y-33675D01*
X181255Y-33967D01*
G01X191986Y-38634D02*
Y-46800D01*
X192860Y-48842D01*
X194170Y-50008D01*
X195698Y-50300D01*
X197226Y-50008D01*
X198536Y-48842D01*
X199410Y-46800D01*
G01Y-50300D02*
Y-38634D01*
G01X209923Y-48259D02*
X211015Y-49425D01*
X212543Y-50300D01*
X213853D01*
X215163Y-49717D01*
X216036Y-48842D01*
X216473Y-47676D01*
X216255Y-45925D01*
X215381Y-45050D01*
X211451Y-43300D01*
X210578Y-41258D01*
X211015Y-39800D01*
X211888Y-38925D01*
X213198Y-38634D01*
X214508Y-38925D01*
X215818Y-39800D01*
G01X230698Y-32800D02*
Y-50300D01*
G01X227641Y-38634D02*
X233755D01*
G01X264388Y-50300D02*
Y-35425D01*
X264825Y-33967D01*
X265698Y-33092D01*
X267008Y-32800D01*
X268318Y-33383D01*
X268973Y-34842D01*
G01X266353Y-39800D02*
X261986D01*
G01X283198Y-50300D02*
X281888Y-50008D01*
X280578Y-48842D01*
X279704Y-46800D01*
X279268Y-44467D01*
X279704Y-42133D01*
X280578Y-40092D01*
X281888Y-38925D01*
X283198Y-38634D01*
X284508Y-38925D01*
X285818Y-40092D01*
X286691Y-42133D01*
X286910Y-44467D01*
X286691Y-46800D01*
X285818Y-48842D01*
X284508Y-50008D01*
X283198Y-50300D01*
G01X297641D02*
Y-38634D01*
G01Y-40967D02*
X298733Y-39800D01*
X299825Y-38925D01*
X301353Y-38634D01*
X302444Y-38925D01*
X303755Y-39800D01*
G01X331113Y-55550D02*
X332423Y-56133D01*
X334170Y-55550D01*
X335261Y-54384D01*
X336135Y-52925D01*
X337444Y-48259D01*
X340283Y-38634D01*
G01X333296D02*
X337444Y-48259D01*
G01X353198Y-50300D02*
X351888Y-50008D01*
X350578Y-48842D01*
X349704Y-46800D01*
X349268Y-44467D01*
X349704Y-42133D01*
X350578Y-40092D01*
X351888Y-38925D01*
X353198Y-38634D01*
X354508Y-38925D01*
X355818Y-40092D01*
X356691Y-42133D01*
X356910Y-44467D01*
X356691Y-46800D01*
X355818Y-48842D01*
X354508Y-50008D01*
X353198Y-50300D01*
G01X366986Y-38634D02*
Y-46800D01*
X367860Y-48842D01*
X369170Y-50008D01*
X370698Y-50300D01*
X372226Y-50008D01*
X373536Y-48842D01*
X374410Y-46800D01*
G01Y-50300D02*
Y-38634D01*
G01X385141Y-50300D02*
Y-38634D01*
G01Y-40967D02*
X386233Y-39800D01*
X387325Y-38925D01*
X388853Y-38634D01*
X389944Y-38925D01*
X391255Y-39800D01*
G01X420141Y-50300D02*
Y-38634D01*
G01Y-40967D02*
X421233Y-39800D01*
X422325Y-38925D01*
X423853Y-38634D01*
X424944Y-38925D01*
X426255Y-39800D01*
G01X437423Y-42425D02*
X444410D01*
X443755Y-40383D01*
X442663Y-39217D01*
X441135Y-38634D01*
X439606Y-38925D01*
X438296Y-39800D01*
X437423Y-41842D01*
X436986Y-43592D01*
Y-45342D01*
X437423Y-47092D01*
X438515Y-48842D01*
X439825Y-50008D01*
X441353Y-50300D01*
X442881Y-49717D01*
X444410Y-47967D01*
G01X456888Y-50300D02*
Y-35425D01*
X457325Y-33967D01*
X458198Y-33092D01*
X459508Y-32800D01*
X460818Y-33383D01*
X461473Y-34842D01*
G01X458853Y-39800D02*
X454486D01*
G01X472423Y-42425D02*
X479410D01*
X478755Y-40383D01*
X477663Y-39217D01*
X476135Y-38634D01*
X474606Y-38925D01*
X473296Y-39800D01*
X472423Y-41842D01*
X471986Y-43592D01*
Y-45342D01*
X472423Y-47092D01*
X473515Y-48842D01*
X474825Y-50008D01*
X476353Y-50300D01*
X477881Y-49717D01*
X479410Y-47967D01*
G01X490141Y-50300D02*
Y-38634D01*
G01Y-40967D02*
X491233Y-39800D01*
X492325Y-38925D01*
X493853Y-38634D01*
X494944Y-38925D01*
X496255Y-39800D01*
G01X507423Y-42425D02*
X514410D01*
X513755Y-40383D01*
X512663Y-39217D01*
X511135Y-38634D01*
X509606Y-38925D01*
X508296Y-39800D01*
X507423Y-41842D01*
X506986Y-43592D01*
Y-45342D01*
X507423Y-47092D01*
X508515Y-48842D01*
X509825Y-50008D01*
X511353Y-50300D01*
X512881Y-49717D01*
X514410Y-47967D01*
G01X524486Y-50300D02*
Y-38634D01*
G01Y-41550D02*
X525360Y-40092D01*
X526670Y-38925D01*
X528416Y-38634D01*
X529944Y-38925D01*
X531255Y-40092D01*
X531910Y-42133D01*
Y-50300D01*
G01X549191Y-40092D02*
X547663Y-38925D01*
X546353Y-38634D01*
X544606Y-39217D01*
X543296Y-40383D01*
X542423Y-42425D01*
X542204Y-44467D01*
X542423Y-46509D01*
X543296Y-48259D01*
X544606Y-49717D01*
X546353Y-50300D01*
X547881Y-49717D01*
X549191Y-48550D01*
G01X559923Y-42425D02*
X566910D01*
X566255Y-40383D01*
X565163Y-39217D01*
X563635Y-38634D01*
X562106Y-38925D01*
X560796Y-39800D01*
X559923Y-41842D01*
X559486Y-43592D01*
Y-45342D01*
X559923Y-47092D01*
X561015Y-48842D01*
X562325Y-50008D01*
X563853Y-50300D01*
X565381Y-49717D01*
X566910Y-47967D01*
G01X598198Y-32800D02*
Y-50300D01*
G01X595141Y-38634D02*
X601255D01*
G01X615698Y-50300D02*
X614388Y-50008D01*
X613078Y-48842D01*
X612204Y-46800D01*
X611768Y-44467D01*
X612204Y-42133D01*
X613078Y-40092D01*
X614388Y-38925D01*
X615698Y-38634D01*
X617008Y-38925D01*
X618318Y-40092D01*
X619191Y-42133D01*
X619410Y-44467D01*
X619191Y-46800D01*
X618318Y-48842D01*
X617008Y-50008D01*
X615698Y-50300D01*
G01X649388D02*
Y-35425D01*
X649825Y-33967D01*
X650698Y-33092D01*
X652008Y-32800D01*
X653318Y-33383D01*
X653973Y-34842D01*
G01X651353Y-39800D02*
X646986D01*
G01X668198Y-38634D02*
Y-50300D01*
G01Y-33967D02*
X667761Y-33675D01*
Y-33092D01*
X668198Y-32800D01*
X668635Y-33092D01*
Y-33675D01*
X668198Y-33967D01*
G01X681986Y-50300D02*
Y-38634D01*
G01Y-41550D02*
X682860Y-40092D01*
X684170Y-38925D01*
X685916Y-38634D01*
X687444Y-38925D01*
X688755Y-40092D01*
X689410Y-42133D01*
Y-50300D01*
G01X707128Y-32800D02*
Y-50300D01*
G01Y-47676D02*
X706255Y-49134D01*
X704944Y-50008D01*
X703416Y-50300D01*
X701670Y-49717D01*
X700360Y-48259D01*
X699486Y-46509D01*
X699268Y-44467D01*
X699486Y-42425D01*
X700360Y-40675D01*
X701670Y-39217D01*
X703416Y-38634D01*
X704944Y-38925D01*
X706036Y-39509D01*
X707128Y-40675D01*
G01X738198Y-32800D02*
Y-50300D01*
G01X735141Y-38634D02*
X741255D01*
G01X751986Y-50300D02*
Y-32800D01*
G01Y-41258D02*
X753078Y-39800D01*
X754170Y-38925D01*
X755916Y-38634D01*
X757226Y-38925D01*
X758755Y-40092D01*
X759410Y-41842D01*
Y-50300D01*
G01X769923Y-42425D02*
X776910D01*
X776255Y-40383D01*
X775163Y-39217D01*
X773635Y-38634D01*
X772106Y-38925D01*
X770796Y-39800D01*
X769923Y-41842D01*
X769486Y-43592D01*
Y-45342D01*
X769923Y-47092D01*
X771015Y-48842D01*
X772325Y-50008D01*
X773853Y-50300D01*
X775381Y-49717D01*
X776910Y-47967D01*
G01X803613D02*
X805360Y-49425D01*
X807325Y-50300D01*
X809071D01*
X810818Y-49425D01*
X812128Y-47967D01*
X812783Y-45925D01*
X812346Y-43884D01*
X811255Y-42133D01*
X809290Y-40967D01*
X806670Y-40383D01*
X805141Y-39217D01*
X804486Y-37175D01*
X804923Y-35133D01*
X806015Y-33675D01*
X807543Y-32800D01*
X809071D01*
X810600Y-33383D01*
X811910Y-34842D01*
G01X830065Y-50300D02*
X821331D01*
Y-32800D01*
X830065D01*
G01X826571Y-41258D02*
X821331D01*
G01X860698Y-38634D02*
Y-50300D01*
G01Y-33967D02*
X860261Y-33675D01*
Y-33092D01*
X860698Y-32800D01*
X861135Y-33092D01*
Y-33675D01*
X860698Y-33967D01*
G01X871648Y-50300D02*
Y-38634D01*
G01Y-41842D02*
X872303Y-40383D01*
X873395Y-39217D01*
X874923Y-38634D01*
X876451Y-39217D01*
X877543Y-40383D01*
X878198Y-41842D01*
Y-50300D01*
G01Y-41842D02*
X878853Y-40383D01*
X879944Y-39217D01*
X881473Y-38634D01*
X883001Y-39217D01*
X884093Y-40383D01*
X884748Y-42133D01*
Y-50300D01*
G01X891768Y-56133D02*
Y-38634D01*
G01Y-41258D02*
X892860Y-39800D01*
X893951Y-38925D01*
X895698Y-38634D01*
X897226Y-38925D01*
X898755Y-40383D01*
X899410Y-42425D01*
X899628Y-44467D01*
X899410Y-46509D01*
X898755Y-48550D01*
X897444Y-49717D01*
X895698Y-50300D01*
X894170Y-50008D01*
X892641Y-49134D01*
X891768Y-47967D01*
G01X909923Y-42425D02*
X916910D01*
X916255Y-40383D01*
X915163Y-39217D01*
X913635Y-38634D01*
X912106Y-38925D01*
X910796Y-39800D01*
X909923Y-41842D01*
X909486Y-43592D01*
Y-45342D01*
X909923Y-47092D01*
X911015Y-48842D01*
X912325Y-50008D01*
X913853Y-50300D01*
X915381Y-49717D01*
X916910Y-47967D01*
G01X934628Y-32800D02*
Y-50300D01*
G01Y-47676D02*
X933755Y-49134D01*
X932444Y-50008D01*
X930916Y-50300D01*
X929170Y-49717D01*
X927860Y-48259D01*
X926986Y-46509D01*
X926768Y-44467D01*
X926986Y-42425D01*
X927860Y-40675D01*
X929170Y-39217D01*
X930916Y-38634D01*
X932444Y-38925D01*
X933536Y-39509D01*
X934628Y-40675D01*
G01X952128Y-50300D02*
Y-38634D01*
G01Y-40675D02*
X951255Y-39509D01*
X949944Y-38925D01*
X948416Y-38634D01*
X946888Y-39217D01*
X945578Y-40383D01*
X944704Y-42133D01*
X944268Y-44467D01*
X944704Y-46800D01*
X945578Y-48550D01*
X946888Y-49717D01*
X948416Y-50300D01*
X949944Y-50008D01*
X951255Y-49134D01*
X952128Y-47967D01*
G01X961986Y-50300D02*
Y-38634D01*
G01Y-41550D02*
X962860Y-40092D01*
X964170Y-38925D01*
X965916Y-38634D01*
X967444Y-38925D01*
X968755Y-40092D01*
X969410Y-42133D01*
Y-50300D01*
G01X986691Y-40092D02*
X985163Y-38925D01*
X983853Y-38634D01*
X982106Y-39217D01*
X980796Y-40383D01*
X979923Y-42425D01*
X979704Y-44467D01*
X979923Y-46509D01*
X980796Y-48259D01*
X982106Y-49717D01*
X983853Y-50300D01*
X985381Y-49717D01*
X986691Y-48550D01*
G01X997423Y-42425D02*
X1004410D01*
X1003755Y-40383D01*
X1002663Y-39217D01*
X1001135Y-38634D01*
X999606Y-38925D01*
X998296Y-39800D01*
X997423Y-41842D01*
X996986Y-43592D01*
Y-45342D01*
X997423Y-47092D01*
X998515Y-48842D01*
X999825Y-50008D01*
X1001353Y-50300D01*
X1002881Y-49717D01*
X1004410Y-47967D01*
G01X1035698Y-32800D02*
Y-50300D01*
G01X1032641Y-38634D02*
X1038755D01*
G01X1050141Y-50300D02*
Y-38634D01*
G01Y-40967D02*
X1051233Y-39800D01*
X1052325Y-38925D01*
X1053853Y-38634D01*
X1054944Y-38925D01*
X1056255Y-39800D01*
G01X1074628Y-50300D02*
Y-38634D01*
G01Y-40675D02*
X1073755Y-39509D01*
X1072444Y-38925D01*
X1070916Y-38634D01*
X1069388Y-39217D01*
X1068078Y-40383D01*
X1067204Y-42133D01*
X1066768Y-44467D01*
X1067204Y-46800D01*
X1068078Y-48550D01*
X1069388Y-49717D01*
X1070916Y-50300D01*
X1072444Y-50008D01*
X1073755Y-49134D01*
X1074628Y-47967D01*
G01X1091691Y-40092D02*
X1090163Y-38925D01*
X1088853Y-38634D01*
X1087106Y-39217D01*
X1085796Y-40383D01*
X1084923Y-42425D01*
X1084704Y-44467D01*
X1084923Y-46509D01*
X1085796Y-48259D01*
X1087106Y-49717D01*
X1088853Y-50300D01*
X1090381Y-49717D01*
X1091691Y-48550D01*
G01X1102423Y-42425D02*
X1109410D01*
X1108755Y-40383D01*
X1107663Y-39217D01*
X1106135Y-38634D01*
X1104606Y-38925D01*
X1103296Y-39800D01*
X1102423Y-41842D01*
X1101986Y-43592D01*
Y-45342D01*
X1102423Y-47092D01*
X1103515Y-48842D01*
X1104825Y-50008D01*
X1106353Y-50300D01*
X1107881Y-49717D01*
X1109410Y-47967D01*
G01X1119923Y-48259D02*
X1121015Y-49425D01*
X1122543Y-50300D01*
X1123853D01*
X1125163Y-49717D01*
X1126036Y-48842D01*
X1126473Y-47676D01*
X1126255Y-45925D01*
X1125381Y-45050D01*
X1121451Y-43300D01*
X1120578Y-41258D01*
X1121015Y-39800D01*
X1121888Y-38925D01*
X1123198Y-38634D01*
X1124508Y-38925D01*
X1125818Y-39800D01*
G01X1158198Y-38634D02*
Y-50300D01*
G01Y-33967D02*
X1157761Y-33675D01*
Y-33092D01*
X1158198Y-32800D01*
X1158635Y-33092D01*
Y-33675D01*
X1158198Y-33967D01*
G01X1171986Y-50300D02*
Y-38634D01*
G01Y-41550D02*
X1172860Y-40092D01*
X1174170Y-38925D01*
X1175916Y-38634D01*
X1177444Y-38925D01*
X1178755Y-40092D01*
X1179410Y-42133D01*
Y-50300D01*
G01X1210698D02*
Y-32800D01*
G01X1232128Y-50300D02*
Y-38634D01*
G01Y-40675D02*
X1231255Y-39509D01*
X1229944Y-38925D01*
X1228416Y-38634D01*
X1226888Y-39217D01*
X1225578Y-40383D01*
X1224704Y-42133D01*
X1224268Y-44467D01*
X1224704Y-46800D01*
X1225578Y-48550D01*
X1226888Y-49717D01*
X1228416Y-50300D01*
X1229944Y-50008D01*
X1231255Y-49134D01*
X1232128Y-47967D01*
G01X1241113Y-55550D02*
X1242423Y-56133D01*
X1244170Y-55550D01*
X1245261Y-54384D01*
X1246135Y-52925D01*
X1247444Y-48259D01*
X1250283Y-38634D01*
G01X1243296D02*
X1247444Y-48259D01*
G01X1259923Y-42425D02*
X1266910D01*
X1266255Y-40383D01*
X1265163Y-39217D01*
X1263635Y-38634D01*
X1262106Y-38925D01*
X1260796Y-39800D01*
X1259923Y-41842D01*
X1259486Y-43592D01*
Y-45342D01*
X1259923Y-47092D01*
X1261015Y-48842D01*
X1262325Y-50008D01*
X1263853Y-50300D01*
X1265381Y-49717D01*
X1266910Y-47967D01*
G01X1277641Y-50300D02*
Y-38634D01*
G01Y-40967D02*
X1278733Y-39800D01*
X1279825Y-38925D01*
X1281353Y-38634D01*
X1282444Y-38925D01*
X1283755Y-39800D01*
G01X1311331Y-32800D02*
Y-50300D01*
X1320065D01*
G01X1328395Y-46800D02*
X1329704Y-48842D01*
X1331451Y-50008D01*
X1333416Y-50300D01*
X1335163Y-50008D01*
X1336910Y-48550D01*
X1338001Y-46800D01*
X1338220Y-45050D01*
X1337783Y-43009D01*
X1336255Y-41550D01*
X1334726Y-40967D01*
X1332761D01*
G01X1334726D02*
X1336036Y-40092D01*
X1337128Y-38634D01*
X1337565Y-36884D01*
X1337128Y-35133D01*
X1336036Y-33675D01*
X1334071Y-32800D01*
X1332106Y-33092D01*
X1330141Y-34259D01*
G01X1350698Y-50883D02*
X1350261Y-50592D01*
Y-50008D01*
X1350698Y-49717D01*
X1351135Y-50008D01*
Y-50592D01*
X1350698Y-50883D01*
G01X1201883Y1950376D02*
X1207123D01*
G01X1204503D02*
Y1932876D01*
G01X1201883D02*
X1207123D01*
G01X1216326D02*
Y1950376D01*
X1222003Y1935793D01*
X1227680Y1950376D01*
Y1932876D01*
G01X1235136D02*
Y1950376D01*
X1240376D01*
X1242123Y1949501D01*
X1243433Y1947459D01*
X1243870Y1945126D01*
X1243433Y1942793D01*
X1242341Y1941043D01*
X1240376Y1940167D01*
X1235136D01*
G01X1255911Y1927043D02*
X1253728Y1929959D01*
X1252636Y1932876D01*
Y1944542D01*
X1253728Y1947459D01*
X1255911Y1950376D01*
G01X1274503Y1932876D02*
X1272756Y1933168D01*
X1271228Y1934334D01*
X1269918Y1936084D01*
X1269044Y1938126D01*
X1268608Y1940459D01*
Y1942793D01*
X1269044Y1945126D01*
X1269918Y1947168D01*
X1271228Y1948917D01*
X1272756Y1950084D01*
X1274503Y1950376D01*
X1276249Y1950084D01*
X1277778Y1948917D01*
X1279088Y1947168D01*
X1279962Y1945126D01*
X1280398Y1942793D01*
Y1940459D01*
X1279962Y1938126D01*
X1279088Y1936084D01*
X1277778Y1934334D01*
X1276249Y1933168D01*
X1274503Y1932876D01*
G01X1288291D02*
Y1950376D01*
G01Y1941918D02*
X1289383Y1943376D01*
X1290475Y1944251D01*
X1292221Y1944542D01*
X1293531Y1944251D01*
X1295060Y1943084D01*
X1295715Y1941334D01*
Y1932876D01*
G01X1302953D02*
Y1944542D01*
G01Y1941334D02*
X1303608Y1942793D01*
X1304700Y1943959D01*
X1306228Y1944542D01*
X1307756Y1943959D01*
X1308848Y1942793D01*
X1309503Y1941334D01*
Y1932876D01*
G01Y1941334D02*
X1310158Y1942793D01*
X1311249Y1943959D01*
X1312778Y1944542D01*
X1314306Y1943959D01*
X1315398Y1942793D01*
X1316053Y1941043D01*
Y1932876D01*
G01X1328095Y1927043D02*
X1330278Y1929959D01*
X1331370Y1932876D01*
Y1944542D01*
X1330278Y1947459D01*
X1328095Y1950376D01*
G01X1180218Y1969859D02*
X1181965Y1968401D01*
X1183930Y1967526D01*
X1185676D01*
X1187423Y1968401D01*
X1188733Y1969859D01*
X1189388Y1971901D01*
X1188951Y1973942D01*
X1187860Y1975693D01*
X1185895Y1976859D01*
X1183275Y1977443D01*
X1181746Y1978609D01*
X1181091Y1980651D01*
X1181528Y1982693D01*
X1182620Y1984151D01*
X1184148Y1985026D01*
X1185676D01*
X1187205Y1984443D01*
X1188515Y1982984D01*
G01X1206670Y1967526D02*
X1197936D01*
Y1985026D01*
X1206670D01*
G01X1203176Y1976568D02*
X1197936D01*
G01X1234683Y1985026D02*
X1239923D01*
G01X1237303D02*
Y1967526D01*
G01X1234683D02*
X1239923D01*
G01X1249126D02*
Y1985026D01*
X1254803Y1970443D01*
X1260480Y1985026D01*
Y1967526D01*
G01X1267936D02*
Y1985026D01*
X1273176D01*
X1274923Y1984151D01*
X1276233Y1982109D01*
X1276670Y1979776D01*
X1276233Y1977443D01*
X1275141Y1975693D01*
X1273176Y1974817D01*
X1267936D01*
G01X1294170Y1967526D02*
X1285436D01*
Y1985026D01*
X1294170D01*
G01X1290676Y1976568D02*
X1285436D01*
G01X1302500Y1967526D02*
Y1985026D01*
X1306866D01*
X1308613Y1984151D01*
X1309923Y1982984D01*
X1311015Y1981235D01*
X1311888Y1979192D01*
X1312106Y1976276D01*
X1311888Y1973359D01*
X1311015Y1971317D01*
X1309923Y1969567D01*
X1308613Y1968401D01*
X1306866Y1967526D01*
X1302500D01*
G01X1319344D02*
X1324803Y1985026D01*
X1330262Y1967526D01*
G01X1328296Y1973651D02*
X1321309D01*
G01X1337281Y1967526D02*
Y1985026D01*
X1347325Y1967526D01*
Y1985026D01*
G01X1364606Y1983567D02*
X1363296Y1984443D01*
X1361768Y1985026D01*
X1360021D01*
X1358056Y1984151D01*
X1356528Y1982693D01*
X1355436Y1980942D01*
X1354563Y1978026D01*
X1354344Y1975401D01*
X1354781Y1972776D01*
X1355436Y1971026D01*
X1356746Y1969276D01*
X1358275Y1968109D01*
X1359803Y1967526D01*
X1361331D01*
X1362860Y1968109D01*
X1364170Y1968984D01*
X1365262Y1970150D01*
G01X1381670Y1967526D02*
X1372936D01*
Y1985026D01*
X1381670D01*
G01X1378176Y1976568D02*
X1372936D01*
G01X1412303Y1985026D02*
Y1967526D01*
G01X1407281Y1985026D02*
X1417325D01*
G01X1424344Y1967526D02*
X1429803Y1985026D01*
X1435262Y1967526D01*
G01X1433296Y1973651D02*
X1426309D01*
G01X1449049Y1976859D02*
X1449923Y1977734D01*
X1450578Y1979192D01*
X1451015Y1981235D01*
X1450578Y1982984D01*
X1449705Y1984151D01*
X1448176Y1985026D01*
X1442281D01*
Y1967526D01*
X1449486D01*
X1451015Y1968692D01*
X1451888Y1970443D01*
X1452325Y1972484D01*
X1451888Y1974526D01*
X1450578Y1976276D01*
X1449049Y1976859D01*
X1442281D01*
G01X1460436Y1985026D02*
Y1967526D01*
X1469170D01*
G01X1486670D02*
X1477936D01*
Y1985026D01*
X1486670D01*
G01X1483176Y1976568D02*
X1477936D01*
G01X1499803Y1966943D02*
X1499366Y1967234D01*
Y1967818D01*
X1499803Y1968109D01*
X1500240Y1967818D01*
Y1967234D01*
X1499803Y1966943D01*
G01Y1974817D02*
X1499366Y1975109D01*
Y1975693D01*
X1499803Y1975984D01*
X1500240Y1975693D01*
Y1975109D01*
X1499803Y1974817D01*
G01X1530436Y1985026D02*
Y1967526D01*
X1539170D01*
G01X1547500Y1971026D02*
X1548809Y1968984D01*
X1550556Y1967818D01*
X1552521Y1967526D01*
X1554268Y1967818D01*
X1556015Y1969276D01*
X1557106Y1971026D01*
X1557325Y1972776D01*
X1556888Y1974817D01*
X1555360Y1976276D01*
X1553831Y1976859D01*
X1551866D01*
G01X1553831D02*
X1555141Y1977734D01*
X1556233Y1979192D01*
X1556670Y1980942D01*
X1556233Y1982693D01*
X1555141Y1984151D01*
X1553176Y1985026D01*
X1551211Y1984734D01*
X1549246Y1983567D01*
G01X1234700Y1900850D02*
X1236009Y1899392D01*
X1237538Y1898518D01*
X1239503Y1898226D01*
X1241468Y1898809D01*
X1242996Y1899976D01*
X1244088Y1902017D01*
X1244306Y1904351D01*
X1243870Y1906684D01*
X1242778Y1908143D01*
X1241249Y1909309D01*
X1239721Y1909601D01*
X1238193Y1909309D01*
X1236228Y1908143D01*
X1236883Y1915726D01*
X1242778D01*
G01X1257003D02*
X1255256Y1915143D01*
X1253946Y1913684D01*
X1253073Y1911935D01*
X1252418Y1909601D01*
X1252200Y1906976D01*
X1252418Y1904351D01*
X1253073Y1902017D01*
X1253946Y1900267D01*
X1255256Y1898809D01*
X1257003Y1898226D01*
X1258749Y1898809D01*
X1260060Y1900267D01*
X1260933Y1902017D01*
X1261588Y1904351D01*
X1261806Y1906976D01*
X1261588Y1909601D01*
X1260933Y1911935D01*
X1260060Y1913684D01*
X1258749Y1915143D01*
X1257003Y1915726D01*
G01X1274503Y1897643D02*
X1274066Y1897934D01*
Y1898518D01*
X1274503Y1898809D01*
X1274940Y1898518D01*
Y1897934D01*
X1274503Y1897643D01*
G01X1292003Y1915726D02*
X1290256Y1915143D01*
X1288946Y1913684D01*
X1288073Y1911935D01*
X1287418Y1909601D01*
X1287200Y1906976D01*
X1287418Y1904351D01*
X1288073Y1902017D01*
X1288946Y1900267D01*
X1290256Y1898809D01*
X1292003Y1898226D01*
X1293749Y1898809D01*
X1295060Y1900267D01*
X1295933Y1902017D01*
X1296588Y1904351D01*
X1296806Y1906976D01*
X1296588Y1909601D01*
X1295933Y1911935D01*
X1295060Y1913684D01*
X1293749Y1915143D01*
X1292003Y1915726D01*
G01X1372953Y1950376D02*
X1376009Y1932876D01*
X1379503Y1950376D01*
X1382996Y1932876D01*
X1386053Y1950376D01*
G01X1394383D02*
X1399623D01*
G01X1397003D02*
Y1932876D01*
G01X1394383D02*
X1399623D01*
G01X1409700D02*
Y1950376D01*
X1414066D01*
X1415813Y1949501D01*
X1417123Y1948334D01*
X1418215Y1946585D01*
X1419088Y1944542D01*
X1419306Y1941626D01*
X1419088Y1938709D01*
X1418215Y1936667D01*
X1417123Y1934917D01*
X1415813Y1933751D01*
X1414066Y1932876D01*
X1409700D01*
G01X1432003Y1950376D02*
Y1932876D01*
G01X1426981Y1950376D02*
X1437025D01*
G01X1444918Y1932876D02*
Y1950376D01*
G01X1454088D02*
Y1932876D01*
G01Y1941626D02*
X1444918D01*
G01X1465911Y1927043D02*
X1463728Y1929959D01*
X1462636Y1932876D01*
Y1944542D01*
X1463728Y1947459D01*
X1465911Y1950376D01*
G01X1477953Y1932876D02*
Y1944542D01*
G01Y1941334D02*
X1478608Y1942793D01*
X1479700Y1943959D01*
X1481228Y1944542D01*
X1482756Y1943959D01*
X1483848Y1942793D01*
X1484503Y1941334D01*
Y1932876D01*
G01Y1941334D02*
X1485158Y1942793D01*
X1486249Y1943959D01*
X1487778Y1944542D01*
X1489306Y1943959D01*
X1490398Y1942793D01*
X1491053Y1941043D01*
Y1932876D01*
G01X1502003Y1944542D02*
Y1932876D01*
G01Y1949209D02*
X1501566Y1949501D01*
Y1950084D01*
X1502003Y1950376D01*
X1502440Y1950084D01*
Y1949501D01*
X1502003Y1949209D01*
G01X1519503Y1932876D02*
Y1950376D01*
G01X1533728Y1934917D02*
X1534820Y1933751D01*
X1536348Y1932876D01*
X1537658D01*
X1538968Y1933459D01*
X1539841Y1934334D01*
X1540278Y1935500D01*
X1540060Y1937251D01*
X1539186Y1938126D01*
X1535256Y1939876D01*
X1534383Y1941918D01*
X1534820Y1943376D01*
X1535693Y1944251D01*
X1537003Y1944542D01*
X1538313Y1944251D01*
X1539623Y1943376D01*
G01X1555595Y1927043D02*
X1557778Y1929959D01*
X1558870Y1932876D01*
Y1944542D01*
X1557778Y1947459D01*
X1555595Y1950376D01*
G01X1445355Y1905517D02*
X1446883Y1907559D01*
X1448193Y1908726D01*
X1449940Y1909309D01*
X1451468Y1908726D01*
X1452560Y1907559D01*
X1453433Y1905809D01*
X1453651Y1903768D01*
X1453433Y1902017D01*
X1452560Y1900267D01*
X1451249Y1898809D01*
X1449721Y1898226D01*
X1447975Y1898809D01*
X1446446Y1900559D01*
X1445573Y1903184D01*
X1445355Y1906101D01*
X1445791Y1909892D01*
X1446446Y1911935D01*
X1447538Y1913976D01*
X1449066Y1915434D01*
X1450595Y1915726D01*
X1452123Y1915143D01*
X1453215Y1913684D01*
G01X1467003Y1897643D02*
X1466566Y1897934D01*
Y1898518D01*
X1467003Y1898809D01*
X1467440Y1898518D01*
Y1897934D01*
X1467003Y1897643D01*
G01X1484503Y1915726D02*
X1482756Y1915143D01*
X1481446Y1913684D01*
X1480573Y1911935D01*
X1479918Y1909601D01*
X1479700Y1906976D01*
X1479918Y1904351D01*
X1480573Y1902017D01*
X1481446Y1900267D01*
X1482756Y1898809D01*
X1484503Y1898226D01*
X1486249Y1898809D01*
X1487560Y1900267D01*
X1488433Y1902017D01*
X1489088Y1904351D01*
X1489306Y1906976D01*
X1489088Y1909601D01*
X1488433Y1911935D01*
X1487560Y1913684D01*
X1486249Y1915143D01*
X1484503Y1915726D01*
G01X1607003Y1950376D02*
Y1932876D01*
G01X1601981Y1950376D02*
X1612025D01*
G01X1624503Y1932876D02*
Y1940751D01*
X1620136Y1950376D01*
G01X1628870D02*
X1624503Y1940751D01*
G01X1637636Y1932876D02*
Y1950376D01*
X1642876D01*
X1644623Y1949501D01*
X1645933Y1947459D01*
X1646370Y1945126D01*
X1645933Y1942793D01*
X1644841Y1941043D01*
X1642876Y1940167D01*
X1637636D01*
G01X1663870Y1932876D02*
X1655136D01*
Y1950376D01*
X1663870D01*
G01X1660376Y1941918D02*
X1655136D01*
G01X1619918Y1900559D02*
X1621665Y1899101D01*
X1623630Y1898226D01*
X1625376D01*
X1627123Y1899101D01*
X1628433Y1900559D01*
X1629088Y1902601D01*
X1628651Y1904642D01*
X1627560Y1906393D01*
X1625595Y1907559D01*
X1622975Y1908143D01*
X1621446Y1909309D01*
X1620791Y1911351D01*
X1621228Y1913393D01*
X1622320Y1914851D01*
X1623848Y1915726D01*
X1625376D01*
X1626905Y1915143D01*
X1628215Y1913684D01*
G01X1646370Y1898226D02*
X1637636D01*
Y1915726D01*
X1646370D01*
G01X1642876Y1907268D02*
X1637636D01*
G01X1707636Y1932876D02*
Y1950376D01*
X1713095D01*
X1714841Y1949501D01*
X1715933Y1948334D01*
X1716370Y1946001D01*
X1715933Y1943667D01*
X1714623Y1942209D01*
X1713095Y1941334D01*
X1707636D01*
G01X1713095D02*
X1716370Y1932876D01*
G01X1726228Y1940751D02*
X1733215D01*
X1732560Y1942793D01*
X1731468Y1943959D01*
X1729940Y1944542D01*
X1728411Y1944251D01*
X1727101Y1943376D01*
X1726228Y1941334D01*
X1725791Y1939584D01*
Y1937834D01*
X1726228Y1936084D01*
X1727320Y1934334D01*
X1728630Y1933168D01*
X1730158Y1932876D01*
X1731686Y1933459D01*
X1733215Y1935209D01*
G01X1745693Y1932876D02*
Y1947751D01*
X1746130Y1949209D01*
X1747003Y1950084D01*
X1748313Y1950376D01*
X1749623Y1949793D01*
X1750278Y1948334D01*
G01X1747658Y1943376D02*
X1743291D01*
G01X1764503Y1932293D02*
X1764066Y1932584D01*
Y1933168D01*
X1764503Y1933459D01*
X1764940Y1933168D01*
Y1932584D01*
X1764503Y1932293D01*
G01X1795136Y1932876D02*
Y1950376D01*
X1800376D01*
X1802123Y1949501D01*
X1803433Y1947459D01*
X1803870Y1945126D01*
X1803433Y1942793D01*
X1802341Y1941043D01*
X1800376Y1940167D01*
X1795136D01*
G01X1817003Y1932876D02*
Y1950376D01*
G01X1838433Y1932876D02*
Y1944542D01*
G01Y1942501D02*
X1837560Y1943667D01*
X1836249Y1944251D01*
X1834721Y1944542D01*
X1833193Y1943959D01*
X1831883Y1942793D01*
X1831009Y1941043D01*
X1830573Y1938709D01*
X1831009Y1936376D01*
X1831883Y1934626D01*
X1833193Y1933459D01*
X1834721Y1932876D01*
X1836249Y1933168D01*
X1837560Y1934042D01*
X1838433Y1935209D01*
G01X1848291Y1932876D02*
Y1944542D01*
G01Y1941626D02*
X1849165Y1943084D01*
X1850475Y1944251D01*
X1852221Y1944542D01*
X1853749Y1944251D01*
X1855060Y1943084D01*
X1855715Y1941043D01*
Y1932876D01*
G01X1866228Y1940751D02*
X1873215D01*
X1872560Y1942793D01*
X1871468Y1943959D01*
X1869940Y1944542D01*
X1868411Y1944251D01*
X1867101Y1943376D01*
X1866228Y1941334D01*
X1865791Y1939584D01*
Y1937834D01*
X1866228Y1936084D01*
X1867320Y1934334D01*
X1868630Y1933168D01*
X1870158Y1932876D01*
X1871686Y1933459D01*
X1873215Y1935209D01*
G01X1751386Y1915726D02*
Y1898226D01*
X1760120D01*
G01X1769105Y1912809D02*
X1770415Y1914559D01*
X1771943Y1915434D01*
X1773690Y1915726D01*
X1775873Y1915143D01*
X1777401Y1913684D01*
X1777838Y1911935D01*
X1777620Y1910184D01*
X1776746Y1908726D01*
X1772380Y1905809D01*
X1770415Y1903768D01*
X1769105Y1900850D01*
X1768668Y1898226D01*
X1777838D01*
G01X1786823Y1897643D02*
X1794683Y1915726D01*
G01X1803886D02*
Y1898226D01*
X1812620D01*
G01X1828373D02*
Y1915726D01*
X1820294Y1903184D01*
X1831212D01*
G01X1912500Y1932293D02*
X1922106Y1945126D01*
G01X1917303Y1947459D02*
Y1929959D01*
G01X1922106Y1932293D02*
X1912500Y1945126D01*
G01X1910753Y1938709D02*
X1923853D01*
G01X1949465D02*
X1955141D01*
G01X1982500Y1932876D02*
Y1950376D01*
X1986866D01*
X1988613Y1949501D01*
X1989923Y1948334D01*
X1991015Y1946585D01*
X1991888Y1944542D01*
X1992106Y1941626D01*
X1991888Y1938709D01*
X1991015Y1936667D01*
X1989923Y1934917D01*
X1988613Y1933751D01*
X1986866Y1932876D01*
X1982500D01*
G01X2001528Y1940751D02*
X2008515D01*
X2007860Y1942793D01*
X2006768Y1943959D01*
X2005240Y1944542D01*
X2003711Y1944251D01*
X2002401Y1943376D01*
X2001528Y1941334D01*
X2001091Y1939584D01*
Y1937834D01*
X2001528Y1936084D01*
X2002620Y1934334D01*
X2003930Y1933168D01*
X2005458Y1932876D01*
X2006986Y1933459D01*
X2008515Y1935209D01*
G01X2018591Y1932876D02*
Y1944542D01*
G01Y1941626D02*
X2019465Y1943084D01*
X2020775Y1944251D01*
X2022521Y1944542D01*
X2024049Y1944251D01*
X2025360Y1943084D01*
X2026015Y1941043D01*
Y1932876D01*
G01X2039803D02*
X2038493Y1933168D01*
X2037183Y1934334D01*
X2036309Y1936376D01*
X2035873Y1938709D01*
X2036309Y1941043D01*
X2037183Y1943084D01*
X2038493Y1944251D01*
X2039803Y1944542D01*
X2041113Y1944251D01*
X2042423Y1943084D01*
X2043296Y1941043D01*
X2043515Y1938709D01*
X2043296Y1936376D01*
X2042423Y1934334D01*
X2041113Y1933168D01*
X2039803Y1932876D01*
G01X2057303Y1950376D02*
Y1932876D01*
G01X2054246Y1944542D02*
X2060360D01*
G01X2071528Y1940751D02*
X2078515D01*
X2077860Y1942793D01*
X2076768Y1943959D01*
X2075240Y1944542D01*
X2073711Y1944251D01*
X2072401Y1943376D01*
X2071528Y1941334D01*
X2071091Y1939584D01*
Y1937834D01*
X2071528Y1936084D01*
X2072620Y1934334D01*
X2073930Y1933168D01*
X2075458Y1932876D01*
X2076986Y1933459D01*
X2078515Y1935209D01*
G01X2089028Y1934917D02*
X2090120Y1933751D01*
X2091648Y1932876D01*
X2092958D01*
X2094268Y1933459D01*
X2095141Y1934334D01*
X2095578Y1935500D01*
X2095360Y1937251D01*
X2094486Y1938126D01*
X2090556Y1939876D01*
X2089683Y1941918D01*
X2090120Y1943376D01*
X2090993Y1944251D01*
X2092303Y1944542D01*
X2093613Y1944251D01*
X2094923Y1943376D01*
G01X2127303Y1950376D02*
Y1932876D01*
G01X2124246Y1944542D02*
X2130360D01*
G01X2141091Y1932876D02*
Y1950376D01*
G01Y1941918D02*
X2142183Y1943376D01*
X2143275Y1944251D01*
X2145021Y1944542D01*
X2146331Y1944251D01*
X2147860Y1943084D01*
X2148515Y1941334D01*
Y1932876D01*
G01X2166233D02*
Y1944542D01*
G01Y1942501D02*
X2165360Y1943667D01*
X2164049Y1944251D01*
X2162521Y1944542D01*
X2160993Y1943959D01*
X2159683Y1942793D01*
X2158809Y1941043D01*
X2158373Y1938709D01*
X2158809Y1936376D01*
X2159683Y1934626D01*
X2160993Y1933459D01*
X2162521Y1932876D01*
X2164049Y1933168D01*
X2165360Y1934042D01*
X2166233Y1935209D01*
G01X2179803Y1950376D02*
Y1932876D01*
G01X2176746Y1944542D02*
X2182860D01*
G01X2214803Y1950376D02*
Y1932876D01*
G01X2211746Y1944542D02*
X2217860D01*
G01X2228591Y1932876D02*
Y1950376D01*
G01Y1941918D02*
X2229683Y1943376D01*
X2230775Y1944251D01*
X2232521Y1944542D01*
X2233831Y1944251D01*
X2235360Y1943084D01*
X2236015Y1941334D01*
Y1932876D01*
G01X2249803Y1944542D02*
Y1932876D01*
G01Y1949209D02*
X2249366Y1949501D01*
Y1950084D01*
X2249803Y1950376D01*
X2250240Y1950084D01*
Y1949501D01*
X2249803Y1949209D01*
G01X2264028Y1934917D02*
X2265120Y1933751D01*
X2266648Y1932876D01*
X2267958D01*
X2269268Y1933459D01*
X2270141Y1934334D01*
X2270578Y1935500D01*
X2270360Y1937251D01*
X2269486Y1938126D01*
X2265556Y1939876D01*
X2264683Y1941918D01*
X2265120Y1943376D01*
X2265993Y1944251D01*
X2267303Y1944542D01*
X2268613Y1944251D01*
X2269923Y1943376D01*
G01X2299683Y1950376D02*
X2304923D01*
G01X2302303D02*
Y1932876D01*
G01X2299683D02*
X2304923D01*
G01X2313253D02*
Y1944542D01*
G01Y1941334D02*
X2313908Y1942793D01*
X2315000Y1943959D01*
X2316528Y1944542D01*
X2318056Y1943959D01*
X2319148Y1942793D01*
X2319803Y1941334D01*
Y1932876D01*
G01Y1941334D02*
X2320458Y1942793D01*
X2321549Y1943959D01*
X2323078Y1944542D01*
X2324606Y1943959D01*
X2325698Y1942793D01*
X2326353Y1941043D01*
Y1932876D01*
G01X2333373Y1927043D02*
Y1944542D01*
G01Y1941918D02*
X2334465Y1943376D01*
X2335556Y1944251D01*
X2337303Y1944542D01*
X2338831Y1944251D01*
X2340360Y1942793D01*
X2341015Y1940751D01*
X2341233Y1938709D01*
X2341015Y1936667D01*
X2340360Y1934626D01*
X2339049Y1933459D01*
X2337303Y1932876D01*
X2335775Y1933168D01*
X2334246Y1934042D01*
X2333373Y1935209D01*
G01X2351528Y1940751D02*
X2358515D01*
X2357860Y1942793D01*
X2356768Y1943959D01*
X2355240Y1944542D01*
X2353711Y1944251D01*
X2352401Y1943376D01*
X2351528Y1941334D01*
X2351091Y1939584D01*
Y1937834D01*
X2351528Y1936084D01*
X2352620Y1934334D01*
X2353930Y1933168D01*
X2355458Y1932876D01*
X2356986Y1933459D01*
X2358515Y1935209D01*
G01X2376233Y1950376D02*
Y1932876D01*
G01Y1935500D02*
X2375360Y1934042D01*
X2374049Y1933168D01*
X2372521Y1932876D01*
X2370775Y1933459D01*
X2369465Y1934917D01*
X2368591Y1936667D01*
X2368373Y1938709D01*
X2368591Y1940751D01*
X2369465Y1942501D01*
X2370775Y1943959D01*
X2372521Y1944542D01*
X2374049Y1944251D01*
X2375141Y1943667D01*
X2376233Y1942501D01*
G01X2393733Y1932876D02*
Y1944542D01*
G01Y1942501D02*
X2392860Y1943667D01*
X2391549Y1944251D01*
X2390021Y1944542D01*
X2388493Y1943959D01*
X2387183Y1942793D01*
X2386309Y1941043D01*
X2385873Y1938709D01*
X2386309Y1936376D01*
X2387183Y1934626D01*
X2388493Y1933459D01*
X2390021Y1932876D01*
X2391549Y1933168D01*
X2392860Y1934042D01*
X2393733Y1935209D01*
G01X2403591Y1932876D02*
Y1944542D01*
G01Y1941626D02*
X2404465Y1943084D01*
X2405775Y1944251D01*
X2407521Y1944542D01*
X2409049Y1944251D01*
X2410360Y1943084D01*
X2411015Y1941043D01*
Y1932876D01*
G01X2428296Y1943084D02*
X2426768Y1944251D01*
X2425458Y1944542D01*
X2423711Y1943959D01*
X2422401Y1942793D01*
X2421528Y1940751D01*
X2421309Y1938709D01*
X2421528Y1936667D01*
X2422401Y1934917D01*
X2423711Y1933459D01*
X2425458Y1932876D01*
X2426986Y1933459D01*
X2428296Y1934626D01*
G01X2439028Y1940751D02*
X2446015D01*
X2445360Y1942793D01*
X2444268Y1943959D01*
X2442740Y1944542D01*
X2441211Y1944251D01*
X2439901Y1943376D01*
X2439028Y1941334D01*
X2438591Y1939584D01*
Y1937834D01*
X2439028Y1936084D01*
X2440120Y1934334D01*
X2441430Y1933168D01*
X2442958Y1932876D01*
X2444486Y1933459D01*
X2446015Y1935209D01*
G01X1987303Y1909892D02*
Y1898226D01*
G01Y1914559D02*
X1986866Y1914851D01*
Y1915434D01*
X1987303Y1915726D01*
X1987740Y1915434D01*
Y1914851D01*
X1987303Y1914559D01*
G01X2001528Y1900267D02*
X2002620Y1899101D01*
X2004148Y1898226D01*
X2005458D01*
X2006768Y1898809D01*
X2007641Y1899684D01*
X2008078Y1900850D01*
X2007860Y1902601D01*
X2006986Y1903476D01*
X2003056Y1905226D01*
X2002183Y1907268D01*
X2002620Y1908726D01*
X2003493Y1909601D01*
X2004803Y1909892D01*
X2006113Y1909601D01*
X2007423Y1908726D01*
G01X2034781Y1898226D02*
Y1915726D01*
X2044825Y1898226D01*
Y1915726D01*
G01X2057303Y1898226D02*
X2055556Y1898518D01*
X2054028Y1899684D01*
X2052718Y1901434D01*
X2051844Y1903476D01*
X2051408Y1905809D01*
Y1908143D01*
X2051844Y1910476D01*
X2052718Y1912518D01*
X2054028Y1914267D01*
X2055556Y1915434D01*
X2057303Y1915726D01*
X2059049Y1915434D01*
X2060578Y1914267D01*
X2061888Y1912518D01*
X2062762Y1910476D01*
X2063198Y1908143D01*
Y1905809D01*
X2062762Y1903476D01*
X2061888Y1901434D01*
X2060578Y1899684D01*
X2059049Y1898518D01*
X2057303Y1898226D01*
G01X2074803Y1915726D02*
Y1898226D01*
G01X2069781Y1915726D02*
X2079825D01*
G01X2106091Y1909892D02*
Y1901726D01*
X2106965Y1899684D01*
X2108275Y1898518D01*
X2109803Y1898226D01*
X2111331Y1898518D01*
X2112641Y1899684D01*
X2113515Y1901726D01*
G01Y1898226D02*
Y1909892D01*
G01X2124028Y1900267D02*
X2125120Y1899101D01*
X2126648Y1898226D01*
X2127958D01*
X2129268Y1898809D01*
X2130141Y1899684D01*
X2130578Y1900850D01*
X2130360Y1902601D01*
X2129486Y1903476D01*
X2125556Y1905226D01*
X2124683Y1907268D01*
X2125120Y1908726D01*
X2125993Y1909601D01*
X2127303Y1909892D01*
X2128613Y1909601D01*
X2129923Y1908726D01*
G01X2141528Y1906101D02*
X2148515D01*
X2147860Y1908143D01*
X2146768Y1909309D01*
X2145240Y1909892D01*
X2143711Y1909601D01*
X2142401Y1908726D01*
X2141528Y1906684D01*
X2141091Y1904934D01*
Y1903184D01*
X2141528Y1901434D01*
X2142620Y1899684D01*
X2143930Y1898518D01*
X2145458Y1898226D01*
X2146986Y1898809D01*
X2148515Y1900559D01*
G01X2166233Y1915726D02*
Y1898226D01*
G01Y1900850D02*
X2165360Y1899392D01*
X2164049Y1898518D01*
X2162521Y1898226D01*
X2160775Y1898809D01*
X2159465Y1900267D01*
X2158591Y1902017D01*
X2158373Y1904059D01*
X2158591Y1906101D01*
X2159465Y1907851D01*
X2160775Y1909309D01*
X2162521Y1909892D01*
X2164049Y1909601D01*
X2165141Y1909017D01*
X2166233Y1907851D01*
G01X-7874Y0D02*
X-75552D01*
G02X-90552Y15000I0J15000D01*
G01Y519024D01*
G02X-75552Y534024I15000J0D01*
G01X-7874D01*
G01Y1030087D02*
X-75552D01*
G03X-90552Y1015087I0J-15000D01*
G01Y1001780D01*
G03X-75552Y986780I15000J0D01*
G01X-7874D01*
G01Y1992126D02*
X-75552D01*
G03X-90552Y1977126I0J-15000D01*
G01Y1915165D01*
G03X-75552Y1900165I15000J0D01*
G01X-7874D01*
G01X1023228Y1618051D02*
Y1675945D01*
G02X1028701Y1681417I5472J0D01*
G01X1033465D01*
X1037402Y1685354D01*
Y1988189D01*
G03X1033465Y1992126I-3937J0D01*
G01X3937D01*
G03X0Y1988189I0J-3937D01*
G01Y1661189D01*
X1969Y1659220D01*
X17323D01*
G02Y1650559I0J-4331D01*
G01X1969D01*
X0Y1648591D01*
Y1243866D01*
X1969Y1241898D01*
X17323D01*
G02Y1233236I0J-4331D01*
G01X1969D01*
X0Y1231268D01*
Y747803D01*
X1969Y745835D01*
X17323D01*
G02Y737173I0J-4331D01*
G01X1969D01*
X0Y735205D01*
Y3937D01*
G03X3937Y0I3937J0D01*
G01X121260D01*
X127310Y11888D01*
G03X127953Y14567I-5263J2680D01*
G01Y17717D01*
G02X139764I5906J0D01*
G01Y14567D01*
G03X140406Y11888I5906J-1D01*
G01X146457Y0D01*
X1033465D01*
G03X1037402Y3937I0J3937D01*
G01Y1424882D01*
X1033465Y1428819D01*
X1028701D01*
G02X1023228Y1434291I0J5473D01*
G01Y1609902D01*
X1021260Y1611870D01*
X993681D01*
G02Y1616083I0J2107D01*
G01X1021260D01*
X1023228Y1618051D01*
G01X-7874Y39059D02*
G03X0I3937J0D01*
G01Y8350D02*
G03X-7874I-3937J0D01*
G01D02*
Y0D01*
G01Y251657D02*
Y39059D01*
G01X0Y251657D02*
G03X-7874I-3937J0D01*
G01Y282366D02*
G03X0I3937J0D01*
G01X-7874Y494965D02*
Y282366D01*
G01Y525673D02*
G03X0I3937J0D01*
G01Y494965D02*
G03X-7874I-3937J0D01*
G01Y534024D02*
Y525673D01*
G01X0Y993079D02*
G03X-7874I-3937J0D01*
G01Y986780D02*
Y993079D01*
G01Y1023787D02*
G03X0I3937J0D01*
G01X-7874D02*
Y1030087D01*
G01Y1930791D02*
Y1900165D01*
G01X0Y1930791D02*
G03X-7874I-3937J0D01*
G01Y1961500D02*
G03X0I3937J0D01*
G01X-7874Y1992126D02*
Y1961500D01*
G01X129000Y255500D02*
X131900Y258400D01*
G01D02*
X188900D01*
G01X196000Y1070300D02*
X142600D01*
G01D02*
X139300Y1067000D01*
G01X188900Y258400D02*
X224851Y294351D01*
G01D02*
X248068D01*
G01D02*
X259037Y305320D01*
G01X375591Y892909D02*
X198200Y1070300D01*
G01D02*
X196000D01*
G01X259037Y305320D02*
X321220D01*
G01D02*
X342251Y326351D01*
G01X338428Y453122D02*
X297300Y494250D01*
G01D02*
Y505017D01*
G01X342251Y326351D02*
Y341251D01*
G01D02*
X349870Y348870D01*
G01X350137Y451250D02*
X348265Y453122D01*
G01D02*
X338428D01*
G01X379372Y880728D02*
X375591Y884509D01*
G01D02*
Y892909D01*
G01X1045276Y0D02*
X1112953D01*
G03X1127953Y15000I0J15000D01*
G01Y493259D01*
G01X1045276Y25827D02*
G03X1037402I-3937J0D01*
G01X1045276Y0D02*
Y25827D01*
G01X1037402Y56535D02*
G03X1045276I3937J0D01*
G01D02*
Y284882D01*
G01X1037402Y315591D02*
G03X1045276I3937J0D01*
G01Y284882D02*
G03X1037402I-3937J0D01*
G01X1045276Y315591D02*
Y543937D01*
G01D02*
G03X1037402I-3937J0D01*
G01Y574646D02*
G03X1045276I3937J0D01*
G01D02*
Y802992D01*
G01X1037402Y833701D02*
G03X1045276I3937J0D01*
G01Y802992D02*
G03X1037402I-3937J0D01*
G01X1045276Y833701D02*
Y1062047D01*
G01D02*
G03X1037402I-3937J0D01*
G01Y1092756D02*
G03X1045276I3937J0D01*
G01D02*
Y1321102D01*
G01D02*
G03X1037402I-3937J0D01*
G01Y1351811D02*
G03X1045276I3937J0D01*
G01D02*
Y1377638D01*
G01D02*
X1112953D01*
G02X1127953Y1362638I0J-15000D01*
G01Y501133D01*
G01X1045276Y1732598D02*
X1112953D01*
G03X1127953Y1747598I0J15000D01*
G01Y1977126D01*
G03X1112953Y1992126I-15000J0D01*
G01X1045276D01*
G01X1037402Y1767835D02*
G03X1045276I3937J0D01*
G01Y1737126D02*
G03X1037402I-3937J0D01*
G01X1045276Y1767835D02*
Y1956890D01*
G01Y1732598D02*
Y1737126D01*
G01X1037402Y1987598D02*
G03X1045276I3937J0D01*
G01Y1956890D02*
G03X1037402I-3937J0D01*
G01X1045276Y1987598D02*
Y1992126D01*
G01X1127953Y501133D02*
G03Y493259I0J-3937D01*
M02*
